(kicad_pcb
	(version 20241229)
	(generator "pcbnew")
	(generator_version "9.0")
	(general
		(thickness 1.62)
		(legacy_teardrops no)
	)
	(paper "A3")
	(title_block
		(title "COM Express 7 Baseboard")
		(date "2025-02-04")
		(rev "1.1.2")
		(company "Antmicro Ltd")
		(comment 1 "www.antmicro.com")
		(comment 9 "footprints 123-126 of 802")
	)
	(layers
		(0 "F.Cu" signal)
		(4 "In1.Cu" signal)
		(6 "In2.Cu" signal)
		(8 "In3.Cu" signal)
		(10 "In4.Cu" signal)
		(12 "In5.Cu" signal)
		(14 "In6.Cu" signal)
		(2 "B.Cu" signal)
		(9 "F.Adhes" user "F.Adhesive")
		(11 "B.Adhes" user "B.Adhesive")
		(13 "F.Paste" user)
		(15 "B.Paste" user)
		(5 "F.SilkS" user "F.Silkscreen")
		(7 "B.SilkS" user "B.Silkscreen")
		(1 "F.Mask" user)
		(3 "B.Mask" user)
		(17 "Dwgs.User" user "User.Drawings")
		(19 "Cmts.User" user "User.Comments")
		(21 "Eco1.User" user "User.Eco1")
		(23 "Eco2.User" user "User.Eco2")
		(25 "Edge.Cuts" user)
		(27 "Margin" user)
		(31 "F.CrtYd" user "F.Courtyard")
		(29 "B.CrtYd" user "B.Courtyard")
		(35 "F.Fab" user)
		(33 "B.Fab" user)
	)
	(footprint "antmicro-footprints:SOIC-8_5.3x5.3x2mm_P1.27mm"
		(layer "F.Cu")
		(at 252.922145 161.93 180)
		(descr "8-Pin SOIC 208-mil")
		(property "Reference" "U36"
			(at -1.227855 3.84 180)
			(layer "F.SilkS")
			(effects
				(font
					(size 0.7 0.7)
					(thickness 0.15)
				)
				(justify right top)
			)
		)
		(property "Value" "W25Q32FV_SOIC-8"
			(at 0 3.8 0)
			(layer "F.Fab")
			(effects
				(font
					(size 0.7 0.7)
					(thickness 0.15)
				)
				(justify right top)
			)
		)
		(property "Datasheet" "https://media.digikey.com/pdf/Data%20Sheets/Winbond%20PDFs/W25Q32FV.pdf"
			(at 0 0 0)
			(layer "F.Fab")
			(hide yes)
			(effects
				(font
					(size 1.27 1.27)
					(thickness 0.15)
				)
			)
		)
		(property "Author" "Antmicro"
			(at 308.762145 -27.337855 90)
			(layer "F.Fab")
			(hide yes)
			(effects
				(font
					(size 1 1)
					(thickness 0.15)
				)
			)
		)
		(property "License" "Apache-2.0"
			(at 308.762145 -27.337855 90)
			(layer "F.Fab")
			(hide yes)
			(effects
				(font
					(size 1 1)
					(thickness 0.15)
				)
			)
		)
		(property "MPN" "W25Q32FVSSIG"
			(at 308.762145 -27.337855 90)
			(layer "F.Fab")
			(hide yes)
			(effects
				(font
					(size 1 1)
					(thickness 0.15)
				)
			)
		)
		(property "Manufacturer" "Winbond"
			(at 308.762145 -27.337855 90)
			(layer "F.Fab")
			(hide yes)
			(effects
				(font
					(size 1 1)
					(thickness 0.15)
				)
			)
		)
		(sheetname "Com Express 7 MGMT")
		(sheetfile "com_express_7_mgmt.kicad_sch")
		(attr smd)
		(fp_line
			(start -2.8 -2.641)
			(end -4.4 -2.641)
			(stroke
				(width 0.15)
				(type solid)
			)
			(layer "F.SilkS")
		)
		(fp_circle
			(center -4.85 -1.905)
			(end -4.8 -1.855)
			(stroke
				(width 0.15)
				(type solid)
			)
			(fill yes)
			(layer "F.SilkS")
		)
		(fp_rect
			(start 4.675 -3)
			(end -4.675 3)
			(stroke
				(width 0.05)
				(type solid)
			)
			(fill no)
			(layer "F.CrtYd")
		)
		(fp_line
			(start 2.64 2.64)
			(end -2.641 2.64)
			(stroke
				(width 0.15)
				(type solid)
			)
			(layer "F.Fab")
		)
		(fp_line
			(start 2.64 -2.641)
			(end 2.64 2.64)
			(stroke
				(width 0.15)
				(type solid)
			)
			(layer "F.Fab")
		)
		(fp_line
			(start -2.641 2.64)
			(end -2.641 -2.641)
			(stroke
				(width 0.15)
				(type solid)
			)
			(layer "F.Fab")
		)
		(fp_line
			(start -2.641 -1.371)
			(end -1.371 -2.641)
			(stroke
				(width 0.15)
				(type solid)
			)
			(layer "F.Fab")
		)
		(fp_line
			(start -2.641 -2.641)
			(end 2.64 -2.641)
			(stroke
				(width 0.15)
				(type solid)
			)
			(layer "F.Fab")
		)
		(pad "1" smd roundrect
			(at -3.601 -1.905 270)
			(size 0.65 1.65)
			(layers "F.Cu" "F.Mask" "F.Paste")
			(roundrect_rratio 0.25)
			(net 397 "/Com Express 7 MGMT/SPI.~{CS}")
			(pinfunction "~{CS}")
			(pintype "input")
			(teardrops
				(best_length_ratio 0.2)
				(max_length 1)
				(best_width_ratio 0.9)
				(max_width 2)
				(curved_edges yes)
				(filter_ratio 0.9)
				(enabled yes)
				(allow_two_segments yes)
				(prefer_zone_connections yes)
			)
		)
		(pad "2" smd roundrect
			(at -3.601 -0.635 270)
			(size 0.65 1.65)
			(layers "F.Cu" "F.Mask" "F.Paste")
			(roundrect_rratio 0.25)
			(net 338 "/Com Express 7 MGMT/SPI.MISO")
			(pinfunction "SO(D1)")
			(pintype "bidirectional")
			(teardrops
				(best_length_ratio 0.2)
				(max_length 1)
				(best_width_ratio 0.9)
				(max_width 2)
				(curved_edges yes)
				(filter_ratio 0.9)
				(enabled yes)
				(allow_two_segments yes)
				(prefer_zone_connections yes)
			)
		)
		(pad "3" smd roundrect
			(at -3.601 0.633 270)
			(size 0.65 1.65)
			(layers "F.Cu" "F.Mask" "F.Paste")
			(roundrect_rratio 0.25)
			(net 601 "Net-(U36-~{WP}(D2))")
			(pinfunction "~{WP}(D2)")
			(pintype "bidirectional")
			(teardrops
				(best_length_ratio 0.2)
				(max_length 1)
				(best_width_ratio 0.9)
				(max_width 2)
				(curved_edges yes)
				(filter_ratio 0.9)
				(enabled yes)
				(allow_two_segments yes)
				(prefer_zone_connections yes)
			)
		)
		(pad "4" smd roundrect
			(at -3.601 1.904 270)
			(size 0.65 1.65)
			(layers "F.Cu" "F.Mask" "F.Paste")
			(roundrect_rratio 0.25)
			(net 1 "GND")
			(pinfunction "GND")
			(pintype "power_in")
			(teardrops
				(best_length_ratio 0.2)
				(max_length 1)
				(best_width_ratio 0.9)
				(max_width 2)
				(curved_edges yes)
				(filter_ratio 0.9)
				(enabled yes)
				(allow_two_segments yes)
				(prefer_zone_connections yes)
			)
		)
		(pad "5" smd roundrect
			(at 3.6 1.904 270)
			(size 0.65 1.65)
			(layers "F.Cu" "F.Mask" "F.Paste")
			(roundrect_rratio 0.25)
			(net 341 "/Com Express 7 MGMT/SPI.MOSI")
			(pinfunction "SI(D0)")
			(pintype "bidirectional")
			(teardrops
				(best_length_ratio 0.2)
				(max_length 1)
				(best_width_ratio 0.9)
				(max_width 2)
				(curved_edges yes)
				(filter_ratio 0.9)
				(enabled yes)
				(allow_two_segments yes)
				(prefer_zone_connections yes)
			)
		)
		(pad "6" smd roundrect
			(at 3.6 0.633 270)
			(size 0.65 1.65)
			(layers "F.Cu" "F.Mask" "F.Paste")
			(roundrect_rratio 0.25)
			(net 340 "/Com Express 7 MGMT/SPI.CLK")
			(pinfunction "SCK")
			(pintype "input")
			(teardrops
				(best_length_ratio 0.2)
				(max_length 1)
				(best_width_ratio 0.9)
				(max_width 2)
				(curved_edges yes)
				(filter_ratio 0.9)
				(enabled yes)
				(allow_two_segments yes)
				(prefer_zone_connections yes)
			)
		)
		(pad "7" smd roundrect
			(at 3.6 -0.635 270)
			(size 0.65 1.65)
			(layers "F.Cu" "F.Mask" "F.Paste")
			(roundrect_rratio 0.25)
			(net 600 "Net-(U36-~{HOLD}(D3))")
			(pinfunction "~{HOLD}(D3)")
			(pintype "bidirectional")
			(teardrops
				(best_length_ratio 0.2)
				(max_length 1)
				(best_width_ratio 0.9)
				(max_width 2)
				(curved_edges yes)
				(filter_ratio 0.9)
				(enabled yes)
				(allow_two_segments yes)
				(prefer_zone_connections yes)
			)
		)
		(pad "8" smd roundrect
			(at 3.6 -1.905 270)
			(size 0.65 1.65)
			(layers "F.Cu" "F.Mask" "F.Paste")
			(roundrect_rratio 0.25)
			(net 85 "/Com Express 7 MGMT/MAFS_POWER")
			(pinfunction "VCC")
			(pintype "power_in")
			(teardrops
				(best_length_ratio 0.2)
				(max_length 1)
				(best_width_ratio 0.9)
				(max_width 2)
				(curved_edges yes)
				(filter_ratio 0.9)
				(enabled yes)
				(allow_two_segments yes)
				(prefer_zone_connections yes)
			)
		)
	)
	(footprint "antmicro-footprints:R_0402_1005Metric"
		(layer "F.Cu")
		(at 192.186128 141.609025 135)
		(descr "Resistor SMD 0402")
		(tags "resistor SMD 0402")
		(property "Reference" "R222"
			(at -1.064088 0.369744 135)
			(layer "F.SilkS")
			(effects
				(font
					(size 0.7 0.7)
					(thickness 0.15)
				)
				(justify left top)
			)
		)
		(property "Value" "R_1k_0402"
			(at -1.011843 1.772046 135)
			(layer "F.Fab")
			(effects
				(font
					(size 0.7 0.7)
					(thickness 0.15)
				)
				(justify left top)
			)
		)
		(property "Datasheet" "https://www.bourns.com/docs/product-datasheets/cr.pdf"
			(at 0 0 135)
			(layer "B.Fab")
			(hide yes)
			(effects
				(font
					(size 1.27 1.27)
					(thickness 0.15)
				)
				(justify mirror)
			)
		)
		(property "Author" "Antmicro"
			(at 332.585 55.715 45)
			(layer "F.Fab")
			(hide yes)
			(effects
				(font
					(size 1 1)
					(thickness 0.15)
				)
			)
		)
		(property "License" "Apache-2.0"
			(at 332.585 55.715 45)
			(layer "F.Fab")
			(hide yes)
			(effects
				(font
					(size 1 1)
					(thickness 0.15)
				)
			)
		)
		(property "MPN" "CR0402-FX-1001GLF"
			(at 332.585 55.715 45)
			(layer "F.Fab")
			(hide yes)
			(effects
				(font
					(size 1 1)
					(thickness 0.15)
				)
			)
		)
		(property "Manufacturer" "Bourns"
			(at 332.585 55.715 45)
			(layer "F.Fab")
			(hide yes)
			(effects
				(font
					(size 1 1)
					(thickness 0.15)
				)
			)
		)
		(property "Public" "False"
			(at 332.585 55.715 45)
			(layer "F.Fab")
			(hide yes)
			(effects
				(font
					(size 1 1)
					(thickness 0.15)
				)
			)
		)
		(property "Tolerance" "1%"
			(at 332.585 55.715 45)
			(layer "F.Fab")
			(hide yes)
			(effects
				(font
					(size 1 1)
					(thickness 0.15)
				)
			)
		)
		(property "Val" "1k"
			(at 332.585 55.715 45)
			(layer "F.Fab")
			(hide yes)
			(effects
				(font
					(size 1 1)
					(thickness 0.15)
				)
			)
		)
		(sheetname "PCIe redriver")
		(sheetfile "pcie_redriver.kicad_sch")
		(attr smd dnp)
		(fp_poly
			(pts
				(xy -0.925 -0.47) (xy 0.925 -0.47) (xy 0.925 0.47) (xy -0.925 0.47)
			)
			(stroke
				(width 0.05)
				(type default)
			)
			(fill no)
			(layer "F.CrtYd")
		)
		(fp_poly
			(pts
				(xy -0.5 -0.25) (xy 0.5 -0.25) (xy 0.5 0.25) (xy -0.5 0.25)
			)
			(stroke
				(width 0.15)
				(type solid)
			)
			(fill no)
			(layer "F.Fab")
		)
		(pad "1" smd roundrect
			(at -0.48 0 135)
			(size 0.59 0.64)
			(layers "F.Cu" "F.Mask" "F.Paste")
			(roundrect_rratio 0.25)
			(net 1 "GND")
			(pintype "passive")
			(teardrops
				(best_length_ratio 0.2)
				(max_length 1)
				(best_width_ratio 0.9)
				(max_width 2)
				(curved_edges yes)
				(filter_ratio 0.9)
				(enabled yes)
				(allow_two_segments yes)
				(prefer_zone_connections yes)
			)
		)
		(pad "2" smd roundrect
			(at 0.48 0 135)
			(size 0.59 0.64)
			(layers "F.Cu" "F.Mask" "F.Paste")
			(roundrect_rratio 0.25)
			(net 974 "/PCIe redriver/RX_FG1")
			(pintype "passive")
			(teardrops
				(best_length_ratio 0.2)
				(max_length 1)
				(best_width_ratio 0.9)
				(max_width 2)
				(curved_edges yes)
				(filter_ratio 0.9)
				(enabled yes)
				(allow_two_segments yes)
				(prefer_zone_connections yes)
			)
		)
	)
	(footprint "antmicro-footprints:C_0402_1005Metric"
		(layer "F.Cu")
		(at 117.4 146.301 90)
		(descr "Capacitor SMD 0402")
		(tags "capacitor SMD 0402")
		(property "Reference" "C116"
			(at 10.541 1.6 90)
			(layer "F.SilkS")
			(effects
				(font
					(size 0.7 0.7)
					(thickness 0.15)
				)
				(justify left bottom)
			)
		)
		(property "Value" "C_100n_0402"
			(at -1.022927 2.155213 90)
			(layer "F.Fab")
			(effects
				(font
					(size 0.7 0.7)
					(thickness 0.15)
				)
				(justify left bottom)
			)
		)
		(property "Datasheet" "https://www.murata.com/products/productdetail?partno=GRM155R61H104KE14%23"
			(at 0 0 90)
			(layer "F.Fab")
			(hide yes)
			(effects
				(font
					(size 1.27 1.27)
					(thickness 0.15)
				)
			)
		)
		(property "Author" "Antmicro"
			(at 263.701 28.901 0)
			(layer "F.Fab")
			(hide yes)
			(effects
				(font
					(size 1 1)
					(thickness 0.15)
				)
			)
		)
		(property "Dielectric" "X5R"
			(at 263.701 28.901 0)
			(layer "F.Fab")
			(hide yes)
			(effects
				(font
					(size 1 1)
					(thickness 0.15)
				)
			)
		)
		(property "License" "Apache-2.0"
			(at 263.701 28.901 0)
			(layer "F.Fab")
			(hide yes)
			(effects
				(font
					(size 1 1)
					(thickness 0.15)
				)
			)
		)
		(property "MPN" "GRM155R61H104KE14D"
			(at 263.701 28.901 0)
			(layer "F.Fab")
			(hide yes)
			(effects
				(font
					(size 1 1)
					(thickness 0.15)
				)
			)
		)
		(property "Manufacturer" "Murata"
			(at 263.701 28.901 0)
			(layer "F.Fab")
			(hide yes)
			(effects
				(font
					(size 1 1)
					(thickness 0.15)
				)
			)
		)
		(property "Public" "False"
			(at 263.701 28.901 0)
			(layer "F.Fab")
			(hide yes)
			(effects
				(font
					(size 1 1)
					(thickness 0.15)
				)
			)
		)
		(property "Val" "100n"
			(at 263.701 28.901 0)
			(layer "F.Fab")
			(hide yes)
			(effects
				(font
					(size 1 1)
					(thickness 0.15)
				)
			)
		)
		(property "Voltage" "50V"
			(at 263.701 28.901 0)
			(layer "F.Fab")
			(hide yes)
			(effects
				(font
					(size 1 1)
					(thickness 0.15)
				)
			)
		)
		(sheetname "PCIe redriver")
		(sheetfile "pcie_redriver.kicad_sch")
		(attr smd)
		(fp_rect
			(start -0.925 -0.47)
			(end 0.925 0.47)
			(stroke
				(width 0.05)
				(type default)
			)
			(fill no)
			(layer "F.CrtYd")
		)
		(fp_line
			(start 0.504 -0.25)
			(end 0.504 0.248)
			(stroke
				(width 0.15)
				(type solid)
			)
			(layer "F.Fab")
		)
		(fp_line
			(start -0.494 -0.25)
			(end 0.504 -0.25)
			(stroke
				(width 0.15)
				(type solid)
			)
			(layer "F.Fab")
		)
		(fp_line
			(start 0.504 0.248)
			(end -0.494 0.248)
			(stroke
				(width 0.15)
				(type solid)
			)
			(layer "F.Fab")
		)
		(fp_line
			(start -0.494 0.248)
			(end -0.494 -0.25)
			(stroke
				(width 0.15)
				(type solid)
			)
			(layer "F.Fab")
		)
		(pad "1" smd roundrect
			(at -0.48 0 90)
			(size 0.59 0.64)
			(layers "F.Cu" "F.Mask" "F.Paste")
			(roundrect_rratio 0.25)
			(net 1 "GND")
			(pintype "passive")
			(teardrops
				(best_length_ratio 0.2)
				(max_length 1)
				(best_width_ratio 0.9)
				(max_width 2)
				(curved_edges yes)
				(filter_ratio 0.9)
				(enabled yes)
				(allow_two_segments yes)
				(prefer_zone_connections yes)
			)
		)
		(pad "2" smd roundrect
			(at 0.48 0 90)
			(size 0.59 0.64)
			(layers "F.Cu" "F.Mask" "F.Paste")
			(roundrect_rratio 0.25)
			(net 2 "+3V3")
			(pintype "passive")
			(teardrops
				(best_length_ratio 0.2)
				(max_length 1)
				(best_width_ratio 0.9)
				(max_width 2)
				(curved_edges yes)
				(filter_ratio 0.9)
				(enabled yes)
				(allow_two_segments yes)
				(prefer_zone_connections yes)
			)
		)
	)
	(footprint "antmicro-footprints:R_0402_1005Metric"
		(layer "F.Cu")
		(at 252.665001 87.45)
		(descr "Resistor SMD 0402")
		(tags "resistor SMD 0402")
		(property "Reference" "R149"
			(at -0.865001 0.440001 0)
			(layer "F.SilkS")
			(effects
				(font
					(size 0.7 0.7)
					(thickness 0.15)
				)
				(justify right bottom)
			)
		)
		(property "Value" "R_0R_0402"
			(at -1.011843 1.772047 0)
			(layer "F.Fab")
			(effects
				(font
					(size 0.7 0.7)
					(thickness 0.15)
				)
				(justify left bottom)
			)
		)
		(property "Datasheet" "https://industrial.panasonic.com/cdbs/www-data/pdf/RDA0000/AOA0000C301.pdf"
			(at 0 0 0)
			(layer "F.Fab")
			(hide yes)
			(effects
				(font
					(size 1.27 1.27)
					(thickness 0.15)
				)
			)
		)
		(property "Author" "Antmicro"
			(at 0 0 0)
			(layer "F.Fab")
			(hide yes)
			(effects
				(font
					(size 1 1)
					(thickness 0.15)
				)
			)
		)
		(property "Current" "1A"
			(at 0 0 0)
			(layer "F.Fab")
			(hide yes)
			(effects
				(font
					(size 1 1)
					(thickness 0.15)
				)
			)
		)
		(property "License" "Apache-2.0"
			(at 0 0 0)
			(layer "F.Fab")
			(hide yes)
			(effects
				(font
					(size 1 1)
					(thickness 0.15)
				)
			)
		)
		(property "MPN" "ERJ2GE0R00X"
			(at 0 0 0)
			(layer "F.Fab")
			(hide yes)
			(effects
				(font
					(size 1 1)
					(thickness 0.15)
				)
			)
		)
		(property "Manufacturer" "Panasonic"
			(at 0 0 0)
			(layer "F.Fab")
			(hide yes)
			(effects
				(font
					(size 1 1)
					(thickness 0.15)
				)
			)
		)
		(property "Public" "False"
			(at 0 0 0)
			(layer "F.Fab")
			(hide yes)
			(effects
				(font
					(size 1 1)
					(thickness 0.15)
				)
			)
		)
		(property "Tolerance" ""
			(at 0 0 0)
			(layer "F.Fab")
			(hide yes)
			(effects
				(font
					(size 1 1)
					(thickness 0.15)
				)
			)
		)
		(property "Val" "0R"
			(at 0 0 0)
			(layer "F.Fab")
			(hide yes)
			(effects
				(font
					(size 1 1)
					(thickness 0.15)
				)
			)
		)
		(sheetname "Misc")
		(sheetfile "misc.kicad_sch")
		(attr smd)
		(fp_rect
			(start -0.925 -0.47)
			(end 0.925 0.47)
			(stroke
				(width 0.05)
				(type default)
			)
			(fill no)
			(layer "F.CrtYd")
		)
		(fp_rect
			(start -0.5 -0.25)
			(end 0.5 0.25)
			(stroke
				(width 0.15)
				(type solid)
			)
			(fill no)
			(layer "F.Fab")
		)
		(pad "1" smd roundrect
			(at -0.48 0)
			(size 0.59 0.64)
			(layers "F.Cu" "F.Mask" "F.Paste")
			(roundrect_rratio 0.25)
			(net 65 "+12V")
			(pintype "passive")
			(teardrops
				(best_length_ratio 0.2)
				(max_length 1)
				(best_width_ratio 0.9)
				(max_width 2)
				(curved_edges yes)
				(filter_ratio 0.9)
				(enabled yes)
				(allow_two_segments yes)
				(prefer_zone_connections yes)
			)
		)
		(pad "2" smd roundrect
			(at 0.48 0)
			(size 0.59 0.64)
			(layers "F.Cu" "F.Mask" "F.Paste")
			(roundrect_rratio 0.25)
			(net 591 "Net-(U24-+12V_{IN})")
			(pintype "passive")
			(teardrops
				(best_length_ratio 0.2)
				(max_length 1)
				(best_width_ratio 0.9)
				(max_width 2)
				(curved_edges yes)
				(filter_ratio 0.9)
				(enabled yes)
				(allow_two_segments yes)
				(prefer_zone_connections yes)
			)
		)
	)
)
